# T6G (Grand Teton) — schematic netlist excerpt (pin names and nets, part order shuffled) for the footprints in the layout excerpt that follows; sources: Cadence DE-HDL packaged netlist, KiCad conversion of 04192023_DAF0TMB3IC0_F0TG_MB_C_brd_V02_OCP.brd

C419  Q_CAP  4.7UF 6.3V 20% X6S  pkg 0402  page 345 : A = P0V9_CPU1_RT_2D ; B = GND

Q131  MOSFET_NCH_DUAL  PJT138K IC  pkg SOT363XD  page 125
  S1  = GND
  G1  = GPU_3V3IO_RSVD1_FFU
  D2  = GPU_3V3IO_RSVD1_FFU_ISO
  S2  = GND
  G2  = GPU_3V3IO_RSVD1_FFU_N
  D1  = GPU_3V3IO_RSVD1_FFU_N

(kicad_pcb
	(version 20260206)
	(generator "pcbnew")
	(generator_version "10.0")
	(general
		(thickness 1.6)
		(legacy_teardrops no)
	)
	(paper "A4")
	(title_block
		(title "04192023_DAF0TMB3IC0_F0TG_MB_C_brd_V02_OCP.brd")
		(comment 1 "Grand Teton / footprints 5047-5048 of 8354")
	)
	(layers
		(0 "F.Cu" signal "TOP")
		(4 "In1.Cu" signal "GND")
		(6 "In2.Cu" signal "IN1")
		(8 "In3.Cu" signal "GND1")
		(10 "In4.Cu" signal "IN2")
		(12 "In5.Cu" signal "GND2")
		(14 "In6.Cu" signal "IN3")
		(16 "In7.Cu" signal "GND3")
		(18 "In8.Cu" signal "VCC")
		(20 "In9.Cu" signal "VCC1")
		(22 "In10.Cu" signal "GND4")
		(24 "In11.Cu" signal "IN4")
		(26 "In12.Cu" signal "GND5")
		(28 "In13.Cu" signal "IN5")
		(30 "In14.Cu" signal "GND6")
		(32 "In15.Cu" signal "IN6")
		(34 "In16.Cu" signal "GND7")
		(2 "B.Cu" signal "BOTTOM")
		(9 "F.Adhes" user "F.Adhesive")
		(11 "B.Adhes" user "B.Adhesive")
		(13 "F.Paste" user "Package Geometry/Pastemask Top")
		(15 "B.Paste" user "Package Geometry/Pastemask Bottom")
		(5 "F.SilkS" user "Ref Des/Silkscreen Top")
		(7 "B.SilkS" user "Ref Des/Silkscreen Bottom")
		(1 "F.Mask" user "Board Geometry/Soldermask Top")
		(3 "B.Mask" user "Board Geometry/Soldermask Bottom")
		(17 "Dwgs.User" user "User.Drawings")
		(19 "Cmts.User" user "User.Comments")
		(21 "Eco1.User" user "User.Eco1")
		(23 "Eco2.User" user "User.Eco2")
		(25 "Edge.Cuts" user "Board Geometry/Outline")
		(27 "Margin" user)
		(31 "F.CrtYd" user "Package Geometry/Place Bound Top")
		(29 "B.CrtYd" user "Package Geometry/Place Bound Bottom")
		(35 "F.Fab" user "Ref Des/Assembly Top")
		(33 "B.Fab" user "Ref Des/Assembly Bottom")
	)
	(footprint ""
		(layer "B.Cu")
		(at 153.018998 -390.560052 90)
		(property "Reference" "C419"
			(at 0 0 90)
			(layer "B.SilkS")
			(hide yes)
			(effects
				(font
					(size 1.27 1.27)
				)
				(justify mirror)
			)
		)
		(property "Value" ""
			(at 0 0 90)
			(layer "B.Fab")
			(effects
				(font
					(size 1.27 1.27)
				)
				(justify mirror)
			)
		)
		(duplicate_pad_numbers_are_jumpers no)
		(fp_line
			(start 0.7874 -0.4064)
			(end -0.7874 -0.4064)
			(stroke
				(width 0.1524)
				(type default)
			)
			(layer "B.SilkS")
		)
		(fp_line
			(start -0.7874 -0.4064)
			(end -0.7874 0.4064)
			(stroke
				(width 0.1524)
				(type default)
			)
			(layer "B.SilkS")
		)
		(fp_line
			(start 0.7874 0.4064)
			(end 0.7874 -0.4064)
			(stroke
				(width 0.1524)
				(type default)
			)
			(layer "B.SilkS")
		)
		(fp_line
			(start -0.7874 0.4064)
			(end 0.7874 0.4064)
			(stroke
				(width 0.1524)
				(type default)
			)
			(layer "B.SilkS")
		)
		(fp_line
			(start 0.67945 -0.305054)
			(end 0.12065 -0.305054)
			(stroke
				(width 0.1)
				(type default)
			)
			(layer "B.Fab")
		)
		(fp_line
			(start 0.12065 -0.305054)
			(end 0.12065 -0.2794)
			(stroke
				(width 0.1)
				(type default)
			)
			(layer "B.Fab")
		)
		(fp_line
			(start -0.12065 -0.3048)
			(end -0.67945 -0.3048)
			(stroke
				(width 0.1)
				(type default)
			)
			(layer "B.Fab")
		)
		(fp_line
			(start -0.67945 -0.3048)
			(end -0.67945 0.3048)
			(stroke
				(width 0.1)
				(type default)
			)
			(layer "B.Fab")
		)
		(fp_line
			(start 0.12065 -0.2794)
			(end -0.12065 -0.2794)
			(stroke
				(width 0.1)
				(type default)
			)
			(layer "B.Fab")
		)
		(fp_line
			(start -0.12065 -0.2794)
			(end -0.12065 -0.3048)
			(stroke
				(width 0.1)
				(type default)
			)
			(layer "B.Fab")
		)
		(fp_line
			(start 0.12065 0.2794)
			(end 0.12065 0.3048)
			(stroke
				(width 0.1)
				(type default)
			)
			(layer "B.Fab")
		)
		(fp_line
			(start -0.120396 0.2794)
			(end 0.12065 0.2794)
			(stroke
				(width 0.1)
				(type default)
			)
			(layer "B.Fab")
		)
		(fp_line
			(start 0.67945 0.3048)
			(end 0.67945 -0.305054)
			(stroke
				(width 0.1)
				(type default)
			)
			(layer "B.Fab")
		)
		(fp_line
			(start 0.12065 0.3048)
			(end 0.67945 0.3048)
			(stroke
				(width 0.1)
				(type default)
			)
			(layer "B.Fab")
		)
		(fp_line
			(start -0.120396 0.3048)
			(end -0.120396 0.2794)
			(stroke
				(width 0.1)
				(type default)
			)
			(layer "B.Fab")
		)
		(fp_line
			(start -0.67945 0.3048)
			(end -0.120396 0.3048)
			(stroke
				(width 0.1)
				(type default)
			)
			(layer "B.Fab")
		)
		(pad "1" smd circle
			(at 0.40005 0 270)
			(size 0 0)
			(layers "B.Cu" "B.Mask" "B.Paste")
			(net "P0V9_CPU1_RT_2D")
		)
		(pad "2" smd circle
			(at -0.40005 0 270)
			(size 0 0)
			(layers "B.Cu" "B.Mask" "B.Paste")
			(net "GND")
		)
	)
	(footprint ""
		(layer "B.Cu")
		(at 167.502332 -431.326544 180)
		(property "Reference" "Q131"
			(at -6.290056 0.352552 0)
			(unlocked yes)
			(layer "B.SilkS")
			(effects
				(font
					(size 0.7874 0.5842)
					(thickness 0.1524)
				)
				(justify left mirror)
			)
		)
		(property "Value" ""
			(at 0 0 0)
			(layer "B.Fab")
			(effects
				(font
					(size 1.27 1.27)
				)
				(justify mirror)
			)
		)
		(duplicate_pad_numbers_are_jumpers no)
		(fp_line
			(start 1.332738 1.100074)
			(end 1.332738 -1.100074)
			(stroke
				(width 0.1524)
				(type default)
			)
			(layer "B.SilkS")
		)
		(fp_line
			(start 1.332738 -1.100074)
			(end 0.4826 -1.100074)
			(stroke
				(width 0.1524)
				(type default)
			)
			(layer "B.SilkS")
		)
		(fp_line
			(start 0.4826 -1.100074)
			(end 0 -0.541274)
			(stroke
				(width 0.1524)
				(type default)
			)
			(layer "B.SilkS")
		)
		(fp_line
			(start 0 -0.541274)
			(end -0.4826 -1.100074)
			(stroke
				(width 0.1524)
				(type default)
			)
			(layer "B.SilkS")
		)
		(fp_line
			(start -0.4826 -1.100074)
			(end -1.332738 -1.100074)
			(stroke
				(width 0.1524)
				(type default)
			)
			(layer "B.SilkS")
		)
		(fp_line
			(start -1.332738 1.100074)
			(end 1.332738 1.100074)
			(stroke
				(width 0.1524)
				(type default)
			)
			(layer "B.SilkS")
		)
		(fp_line
			(start -1.332738 -1.100074)
			(end -1.332738 1.100074)
			(stroke
				(width 0.1524)
				(type default)
			)
			(layer "B.SilkS")
		)
		(fp_poly
			(pts
				(xy 1.362456 -1.189482) (xy 2.10693 -1.43764) (xy 1.610614 -1.933956)
			)
			(stroke
				(width 0)
				(type default)
			)
			(fill yes)
			(layer "B.SilkS")
		)
		(fp_line
			(start 0.674878 1.100074)
			(end 0.674878 -1.100074)
			(stroke
				(width 0.1)
				(type default)
			)
			(layer "B.Fab")
		)
		(fp_line
			(start 0.674878 -1.100074)
			(end -0.674878 -1.100074)
			(stroke
				(width 0.1)
				(type default)
			)
			(layer "B.Fab")
		)
		(fp_line
			(start -0.674878 1.100074)
			(end 0.674878 1.100074)
			(stroke
				(width 0.1)
				(type default)
			)
			(layer "B.Fab")
		)
		(fp_line
			(start -0.674878 -1.100074)
			(end -0.674878 1.100074)
			(stroke
				(width 0.1)
				(type default)
			)
			(layer "B.Fab")
		)
		(fp_poly
			(pts
				(xy 2.2352 -0.298958) (xy 2.2352 -1.001014) (xy 1.533144 -0.649986)
			)
			(stroke
				(width 0)
				(type default)
			)
			(fill yes)
			(layer "B.Fab")
		)
		(pad "1" smd rect
			(at 0.94996 -0.649986 270)
			(size 0.4318 0.508)
			(layers "B.Cu" "B.Mask" "B.Paste")
			(net "GND")
		)
		(pad "2" smd rect
			(at 0.94996 0 270)
			(size 0.4318 0.508)
			(layers "B.Cu" "B.Mask" "B.Paste")
			(net "GPU_3V3IO_RSVD1_FFU")
		)
		(pad "3" smd rect
			(at 0.94996 0.649986 270)
			(size 0.4318 0.508)
			(layers "B.Cu" "B.Mask" "B.Paste")
			(net "GPU_3V3IO_RSVD1_FFU_ISO")
		)
		(pad "4" smd rect
			(at -0.94996 0.649986 270)
			(size 0.4318 0.508)
			(layers "B.Cu" "B.Mask" "B.Paste")
			(net "GND")
		)
		(pad "5" smd rect
			(at -0.94996 0 270)
			(size 0.4318 0.508)
			(layers "B.Cu" "B.Mask" "B.Paste")
			(net "GPU_3V3IO_RSVD1_FFU_N")
		)
		(pad "6" smd rect
			(at -0.94996 -0.649986 270)
			(size 0.4318 0.508)
			(layers "B.Cu" "B.Mask" "B.Paste")
			(net "GPU_3V3IO_RSVD1_FFU_N")
		)
	)
)
